# S9S_MB_2U (Grand Teton) — schematic netlist excerpt (pin names and nets, part order shuffled) for the footprints in the layout excerpt that follows; sources: Cadence DE-HDL packaged netlist, KiCad conversion of 03242023_DA0F0TMBIJ0_F0T_Motherboard_J_brd_V01_OCP.brd

R1959  Q_RES  0 5% CHIP  pkg 0402LF  page 14 : A = H_CPU0_PMDOWN_PCH_R2 ; B = H_CPU0_PMDOWN_PCH_R

DB6  TDR_3P  EMPTY  pkg TH2  page 309
  GND  = T1_GND
  IO1  = TDR_SE_40_OHM_BOT
  IO2  = TDR_SE_40_OHM_BOT

PC519_P1_6  Q_CAP  22UF 4V 20% X6S  pkg C0805  page 287 : A = PVCCIN_CPU1 ; B = GND

(kicad_pcb
	(version 20260206)
	(generator "pcbnew")
	(generator_version "10.0")
	(general
		(thickness 1.6)
		(legacy_teardrops no)
	)
	(paper "A4")
	(title_block
		(title "03242023_DA0F0TMBIJ0_F0T_Motherboard_J_brd_V01_OCP.brd")
		(comment 1 "Grand Teton / footprints 6069-6071 of 6105")
	)
	(layers
		(0 "F.Cu" signal "TOP")
		(4 "In1.Cu" signal "GND")
		(6 "In2.Cu" signal "IN1")
		(8 "In3.Cu" signal "GND1")
		(10 "In4.Cu" signal "IN2")
		(12 "In5.Cu" signal "GND2")
		(14 "In6.Cu" signal "IN3")
		(16 "In7.Cu" signal "GND3")
		(18 "In8.Cu" signal "VCC")
		(20 "In9.Cu" signal "VCC1")
		(22 "In10.Cu" signal "GND4")
		(24 "In11.Cu" signal "IN4")
		(26 "In12.Cu" signal "GND5")
		(28 "In13.Cu" signal "IN5")
		(30 "In14.Cu" signal "GND6")
		(32 "In15.Cu" signal "IN6")
		(34 "In16.Cu" signal "GND7")
		(2 "B.Cu" signal "BOTTOM")
		(9 "F.Adhes" user "F.Adhesive")
		(11 "B.Adhes" user "B.Adhesive")
		(13 "F.Paste" user "Package Geometry/Pastemask Top")
		(15 "B.Paste" user "Package Geometry/Pastemask Bottom")
		(5 "F.SilkS" user "Ref Des/Silkscreen Top")
		(7 "B.SilkS" user "Ref Des/Silkscreen Bottom")
		(1 "F.Mask" user "Board Geometry/Soldermask Top")
		(3 "B.Mask" user "Board Geometry/Soldermask Bottom")
		(17 "Dwgs.User" user "User.Drawings")
		(19 "Cmts.User" user "User.Comments")
		(21 "Eco1.User" user "User.Eco1")
		(23 "Eco2.User" user "User.Eco2")
		(25 "Edge.Cuts" user "Board Geometry/Outline")
		(27 "Margin" user)
		(31 "F.CrtYd" user "Package Geometry/Place Bound Top")
		(29 "B.CrtYd" user "Package Geometry/Place Bound Bottom")
		(35 "F.Fab" user "Ref Des/Assembly Top")
		(33 "B.Fab" user "Ref Des/Assembly Bottom")
	)
	(footprint ""
		(layer "B.Cu")
		(at 401.832318 -230.94823 90)
		(property "Reference" "R1959"
			(at 0 0 90)
			(layer "B.SilkS")
			(hide yes)
			(effects
				(font
					(size 1.27 1.27)
				)
				(justify mirror)
			)
		)
		(property "Value" ""
			(at 0 0 90)
			(layer "B.Fab")
			(effects
				(font
					(size 1.27 1.27)
				)
				(justify mirror)
			)
		)
		(duplicate_pad_numbers_are_jumpers no)
		(fp_line
			(start 0.7874 -0.4064)
			(end -0.7874 -0.4064)
			(stroke
				(width 0.1524)
				(type default)
			)
			(layer "B.SilkS")
		)
		(fp_line
			(start -0.7874 -0.4064)
			(end -0.7874 0.4064)
			(stroke
				(width 0.1524)
				(type default)
			)
			(layer "B.SilkS")
		)
		(fp_line
			(start 0.7874 0.4064)
			(end 0.7874 -0.4064)
			(stroke
				(width 0.1524)
				(type default)
			)
			(layer "B.SilkS")
		)
		(fp_line
			(start -0.7874 0.4064)
			(end 0.7874 0.4064)
			(stroke
				(width 0.1524)
				(type default)
			)
			(layer "B.SilkS")
		)
		(fp_line
			(start 0.67945 -0.305054)
			(end 0.12065 -0.305054)
			(stroke
				(width 0.1)
				(type default)
			)
			(layer "B.Fab")
		)
		(fp_line
			(start 0.12065 -0.305054)
			(end 0.12065 -0.2794)
			(stroke
				(width 0.1)
				(type default)
			)
			(layer "B.Fab")
		)
		(fp_line
			(start -0.12065 -0.3048)
			(end -0.67945 -0.3048)
			(stroke
				(width 0.1)
				(type default)
			)
			(layer "B.Fab")
		)
		(fp_line
			(start -0.67945 -0.3048)
			(end -0.67945 0.3048)
			(stroke
				(width 0.1)
				(type default)
			)
			(layer "B.Fab")
		)
		(fp_line
			(start 0.12065 -0.2794)
			(end -0.12065 -0.2794)
			(stroke
				(width 0.1)
				(type default)
			)
			(layer "B.Fab")
		)
		(fp_line
			(start -0.12065 -0.2794)
			(end -0.12065 -0.3048)
			(stroke
				(width 0.1)
				(type default)
			)
			(layer "B.Fab")
		)
		(fp_line
			(start 0.12065 0.2794)
			(end 0.12065 0.3048)
			(stroke
				(width 0.1)
				(type default)
			)
			(layer "B.Fab")
		)
		(fp_line
			(start -0.120396 0.2794)
			(end 0.12065 0.2794)
			(stroke
				(width 0.1)
				(type default)
			)
			(layer "B.Fab")
		)
		(fp_line
			(start 0.67945 0.3048)
			(end 0.67945 -0.305054)
			(stroke
				(width 0.1)
				(type default)
			)
			(layer "B.Fab")
		)
		(fp_line
			(start 0.12065 0.3048)
			(end 0.67945 0.3048)
			(stroke
				(width 0.1)
				(type default)
			)
			(layer "B.Fab")
		)
		(fp_line
			(start -0.120396 0.3048)
			(end -0.120396 0.2794)
			(stroke
				(width 0.1)
				(type default)
			)
			(layer "B.Fab")
		)
		(fp_line
			(start -0.67945 0.3048)
			(end -0.120396 0.3048)
			(stroke
				(width 0.1)
				(type default)
			)
			(layer "B.Fab")
		)
		(pad "1" smd circle
			(at 0.40005 0 270)
			(size 0 0)
			(layers "B.Cu" "B.Mask" "B.Paste")
			(net "H_CPU0_PMDOWN_PCH_R2")
		)
		(pad "2" smd circle
			(at -0.40005 0 270)
			(size 0 0)
			(layers "B.Cu" "B.Mask" "B.Paste")
			(net "H_CPU0_PMDOWN_PCH_R")
		)
	)
	(footprint ""
		(layer "B.Cu")
		(at 85.340952 -328.298048 -90)
		(property "Reference" "PC519_P1_6"
			(at 0 0 90)
			(layer "B.SilkS")
			(hide yes)
			(effects
				(font
					(size 1.27 1.27)
				)
				(justify mirror)
			)
		)
		(property "Value" ""
			(at 0 0 90)
			(layer "B.Fab")
			(effects
				(font
					(size 1.27 1.27)
				)
				(justify mirror)
			)
		)
		(duplicate_pad_numbers_are_jumpers no)
		(fp_line
			(start -1.524 0.762)
			(end 1.524 0.762)
			(stroke
				(width 0.1524)
				(type default)
			)
			(layer "B.SilkS")
		)
		(fp_line
			(start 1.524 0.762)
			(end 1.524 -0.762)
			(stroke
				(width 0.1524)
				(type default)
			)
			(layer "B.SilkS")
		)
		(fp_line
			(start -1.524 -0.762)
			(end -1.524 0.762)
			(stroke
				(width 0.1524)
				(type default)
			)
			(layer "B.SilkS")
		)
		(fp_line
			(start 1.524 -0.762)
			(end -1.524 -0.762)
			(stroke
				(width 0.1524)
				(type default)
			)
			(layer "B.SilkS")
		)
		(fp_line
			(start -1.1049 0.724916)
			(end -1.1049 -0.724916)
			(stroke
				(width 0.1)
				(type default)
			)
			(layer "B.Fab")
		)
		(fp_line
			(start 1.1049 0.724916)
			(end -1.1049 0.724916)
			(stroke
				(width 0.1)
				(type default)
			)
			(layer "B.Fab")
		)
		(fp_line
			(start -1.1049 -0.724916)
			(end 1.1049 -0.724916)
			(stroke
				(width 0.1)
				(type default)
			)
			(layer "B.Fab")
		)
		(fp_line
			(start 1.1049 -0.724916)
			(end 1.1049 0.724916)
			(stroke
				(width 0.1)
				(type default)
			)
			(layer "B.Fab")
		)
		(pad "1" smd rect
			(at 0.889 0 270)
			(size 1.016 1.27)
			(layers "B.Cu" "B.Mask" "B.Paste")
			(net "PVCCIN_CPU1")
		)
		(pad "2" smd rect
			(at -0.889 0 270)
			(size 1.016 1.27)
			(layers "B.Cu" "B.Mask" "B.Paste")
			(net "GND")
		)
	)
	(footprint ""
		(layer "B.Cu")
		(at 490.14253 -427.53788 180)
		(property "Reference" "DB6"
			(at 2.845308 -7.762748 270)
			(unlocked yes)
			(layer "B.SilkS")
			(effects
				(font
					(size 0.7874 0.5842)
					(thickness 0.1524)
				)
				(justify left mirror)
			)
		)
		(property "Value" ""
			(at 0 0 0)
			(layer "B.Fab")
			(effects
				(font
					(size 1.27 1.27)
				)
				(justify mirror)
			)
		)
		(duplicate_pad_numbers_are_jumpers no)
		(fp_line
			(start 3.330702 -4.771136)
			(end -3.330702 -4.771136)
			(stroke
				(width 0.1524)
				(type default)
			)
			(layer "B.SilkS")
		)
		(fp_line
			(start 0 4.011168)
			(end 3.330702 -4.771136)
			(stroke
				(width 0.1524)
				(type default)
			)
			(layer "B.SilkS")
		)
		(fp_line
			(start -3.330702 -4.771136)
			(end 0 4.011168)
			(stroke
				(width 0.1524)
				(type default)
			)
			(layer "B.SilkS")
		)
		(fp_line
			(start 3.330702 -4.771136)
			(end -3.330702 -4.771136)
			(stroke
				(width 0.1)
				(type default)
			)
			(layer "B.Fab")
		)
		(fp_line
			(start 0 4.011168)
			(end 3.330702 -4.771136)
			(stroke
				(width 0.1)
				(type default)
			)
			(layer "B.Fab")
		)
		(fp_line
			(start -3.330702 -4.771136)
			(end 0 4.011168)
			(stroke
				(width 0.1)
				(type default)
			)
			(layer "B.Fab")
		)
		(pad "1" thru_hole circle
			(at 0 0)
			(size 2.159 2.159)
			(drill 1.7018)
			(layers "*.Cu" "*.Mask")
			(remove_unused_layers no)
			(net "T1_GND")
			(clearance 0.0254)
			(thermal_gap 0.0254)
		)
		(pad "2" thru_hole circle
			(at 1.27 -3.348736)
			(size 2.159 2.159)
			(drill 1.7018)
			(layers "*.Cu" "*.Mask")
			(remove_unused_layers no)
			(net "TDR_SE_40_OHM_BOT")
			(clearance 0.0254)
			(thermal_gap 0.0254)
		)
		(pad "3" thru_hole circle
			(at -1.27 -3.348736)
			(size 2.159 2.159)
			(drill 1.7018)
			(layers "*.Cu" "*.Mask")
			(remove_unused_layers no)
			(net "TDR_SE_40_OHM_BOT")
			(clearance 0.0254)
			(thermal_gap 0.0254)
		)
	)
)
